(kicad_pcb
	(version 20241229)
	(generator "pcbnew")
	(generator_version "9.0")
	(general
		(thickness 1.6642)
		(legacy_teardrops no)
	)
	(paper "A3")
	(title_block
		(title "PolarFire SoM")
		(date "2025-07-22")
		(rev "1.1.4")
		(company "Antmicro Ltd")
		(comment 1 "www.antmicro.com")
		(comment 9 "footprint 383 of 470 (J1), pads 96-104 of 104")
	)
	(layers
		(0 "F.Cu" mixed)
		(4 "In1.Cu" power)
		(6 "In2.Cu" signal)
		(8 "In3.Cu" power)
		(10 "In4.Cu" signal)
		(12 "In5.Cu" power)
		(14 "In6.Cu" power)
		(16 "In7.Cu" signal)
		(18 "In8.Cu" power)
		(20 "In9.Cu" signal)
		(22 "In10.Cu" power)
		(24 "In11.Cu" signal)
		(26 "In12.Cu" signal)
		(2 "B.Cu" mixed)
		(9 "F.Adhes" user "F.Adhesive")
		(11 "B.Adhes" user "B.Adhesive")
		(13 "F.Paste" user)
		(15 "B.Paste" user)
		(5 "F.SilkS" user "F.Silkscreen")
		(7 "B.SilkS" user "B.Silkscreen")
		(1 "F.Mask" user)
		(3 "B.Mask" user)
		(17 "Dwgs.User" user "User.Drawings")
		(19 "Cmts.User" user "User.Comments")
		(21 "Eco1.User" user "User.Eco1")
		(23 "Eco2.User" user "User.Eco2")
		(25 "Edge.Cuts" user)
		(27 "Margin" user)
		(31 "F.CrtYd" user "F.Courtyard")
		(29 "B.CrtYd" user "B.Courtyard")
		(35 "F.Fab" user)
		(33 "B.Fab" user)
	)
	(footprint "antmicro-footprints:Conn_Plug_Hirose_DF40_2x50_DF40C-100DP-0.4V"
		(layer "B.Cu")
		(at 199.523 118.838 180)
		(property "Reference" "J1"
			(at -11.337 1.878 0)
			(layer "B.SilkS")
			(effects
				(font
					(size 0.7 0.7)
					(thickness 0.15)
				)
				(justify left bottom mirror)
			)
		)
		(property "Value" "Plug_Hirose_DF40_2x50_DF40C-100DP-0.4V"
			(at 0.001 -2.8 0)
			(layer "B.Fab")
			(hide yes)
			(effects
				(font
					(size 0.7 0.7)
					(thickness 0.15)
				)
				(justify left bottom mirror)
			)
		)
		(property "Datasheet" "https://www.hirose.com/en/product/document?clcode=CL0684-4032-1-51&productname=DF40C-100DP-0.4V(51)&series=DF40&documenttype=2DDrawing&lang=en&documentid=0001001212"
			(at 0 0 180)
			(layer "F.Fab")
			(hide yes)
			(effects
				(font
					(size 1.27 1.27)
					(thickness 0.15)
				)
			)
		)
		(property "Description" "Mezzanine Connector, Header, 0.4 mm, 2 Rows, 100 Contacts, Surface Mount, Phosphor Bronze"
			(at 0 0 180)
			(layer "F.Fab")
			(hide yes)
			(effects
				(font
					(size 1.27 1.27)
					(thickness 0.15)
				)
			)
		)
		(property "Author" "Antmicro"
			(at 399.046 237.676 0)
			(layer "B.Fab")
			(hide yes)
			(effects
				(font
					(size 1 1)
					(thickness 0.15)
				)
				(justify mirror)
			)
		)
		(property "License" "Apache-2.0"
			(at 399.046 237.676 0)
			(layer "B.Fab")
			(hide yes)
			(effects
				(font
					(size 1 1)
					(thickness 0.15)
				)
				(justify mirror)
			)
		)
		(property "MPN" "DF40C-100DP-0.4V(51)"
			(at 399.046 237.676 0)
			(layer "B.Fab")
			(hide yes)
			(effects
				(font
					(size 1 1)
					(thickness 0.15)
				)
				(justify mirror)
			)
		)
		(property "Manufacturer" "Hirose Electric"
			(at 399.046 237.676 0)
			(layer "B.Fab")
			(hide yes)
			(effects
				(font
					(size 1 1)
					(thickness 0.15)
				)
				(justify mirror)
			)
		)
		(property "Pitch" "0.4 mm"
			(at 399.046 237.676 0)
			(layer "B.Fab")
			(hide yes)
			(effects
				(font
					(size 1 1)
					(thickness 0.15)
				)
				(justify mirror)
			)
		)
		(sheetname "/Top Connector/")
		(sheetfile "top-connector.kicad_sch")
		(attr smd)
		(pad "96" smd rect
			(at 9 -1.333 180)
			(size 0.23 0.66)
			(layers "B.Cu" "B.Mask" "B.Paste")
			(net 58 "unconnected-(J1-Pad96)")
			(pintype "passive+no_connect")
		)
		(pad "97" smd rect
			(at 9.401 1.377 180)
			(size 0.23 0.66)
			(layers "B.Cu" "B.Mask" "B.Paste")
			(net 59 "unconnected-(J1-Pad97)")
			(pintype "passive+no_connect")
		)
		(pad "98" smd rect
			(at 9.401 -1.333 180)
			(size 0.23 0.66)
			(layers "B.Cu" "B.Mask" "B.Paste")
			(net 417 "GND")
			(pintype "passive")
		)
		(pad "99" smd rect
			(at 9.803 1.377 180)
			(size 0.23 0.66)
			(layers "B.Cu" "B.Mask" "B.Paste")
			(net 212 "GLOBAL_EN")
			(pintype "passive")
		)
		(pad "100" smd rect
			(at 9.803 -1.333 180)
			(size 0.23 0.66)
			(layers "B.Cu" "B.Mask" "B.Paste")
			(net 61 "unconnected-(J1-Pad100)")
			(pintype "passive+no_connect")
		)
		(pad "MP" smd rect
			(at -10.274 -1.333 180)
			(size 0.35 0.66)
			(layers "B.Cu" "B.Mask" "B.Paste")
			(net 417 "GND")
			(pinfunction "MP")
			(pintype "passive")
		)
		(pad "MP" smd rect
			(at -10.274 1.377 180)
			(size 0.35 0.66)
			(layers "B.Cu" "B.Mask" "B.Paste")
			(net 417 "GND")
			(pinfunction "MP")
			(pintype "passive")
		)
		(pad "MP" smd rect
			(at 10.276 -1.333 180)
			(size 0.35 0.66)
			(layers "B.Cu" "B.Mask" "B.Paste")
			(net 417 "GND")
			(pinfunction "MP")
			(pintype "passive")
		)
		(pad "MP" smd rect
			(at 10.276 1.377 180)
			(size 0.35 0.66)
			(layers "B.Cu" "B.Mask" "B.Paste")
			(net 417 "GND")
			(pinfunction "MP")
			(pintype "passive")
		)
	)
)
